# BASEBOARD_FAB2 (Tioga Pass) — schematic netlist excerpt (pin names and nets, part order shuffled) for the footprints in the layout excerpt that follows; sources: Cadence DE-HDL packaged netlist, KiCad conversion of Wiwynn_Tioga_Pass_MB.brd

C3D14  CAP_A  22.0UF 4V 20% X6S  pkg 0603V  page 76 : A = PVCCMCP_CPU1 ; B = GND
C1F2  CAP  0.22UF 16V 10% X7R  pkg 0402  page 181 : A = P3E_CPU1_PE3_MP_C_TXP<7> ; B = P3E_CPU1_PE3_MP_TXP<7>
C7F11  CAP  1000PF 50V 10% X7R  pkg 0402LF  page 231 : A = PWRGD_PVPP_ABC_R ; B = GND

(kicad_pcb
	(version 20260206)
	(generator "pcbnew")
	(generator_version "10.0")
	(general
		(thickness 1.6)
		(legacy_teardrops no)
	)
	(paper "A4")
	(title_block
		(title "Wiwynn_Tioga_Pass_MB.brd")
		(comment 1 "Tioga Pass / footprints 1373-1375 of 4770")
	)
	(layers
		(0 "F.Cu" signal "TOP")
		(4 "In1.Cu" signal "L2GND")
		(6 "In2.Cu" signal "L3")
		(8 "In3.Cu" signal "L4GND")
		(10 "In4.Cu" signal "L5")
		(12 "In5.Cu" signal "L6GND")
		(14 "In6.Cu" signal "L7VCC")
		(16 "In7.Cu" signal "L8VCC")
		(18 "In8.Cu" signal "L9GND")
		(20 "In9.Cu" signal "L10")
		(22 "In10.Cu" signal "L11GND")
		(24 "In11.Cu" signal "L12")
		(26 "In12.Cu" signal "L13GND")
		(2 "B.Cu" signal "BOTTOM")
		(9 "F.Adhes" user "F.Adhesive")
		(11 "B.Adhes" user "B.Adhesive")
		(13 "F.Paste" user "Package Geometry/Pastemask Top")
		(15 "B.Paste" user "Package Geometry/Pastemask Bottom")
		(5 "F.SilkS" user "Ref Des/Silkscreen Top")
		(7 "B.SilkS" user "Ref Des/Silkscreen Bottom")
		(1 "F.Mask" user "Board Geometry/Soldermask Top")
		(3 "B.Mask" user "Board Geometry/Soldermask Bottom")
		(17 "Dwgs.User" user "User.Drawings")
		(19 "Cmts.User" user "User.Comments")
		(21 "Eco1.User" user "User.Eco1")
		(23 "Eco2.User" user "User.Eco2")
		(25 "Edge.Cuts" user "Board Geometry/Outline")
		(27 "Margin" user)
		(31 "F.CrtYd" user "Package Geometry/Place Bound Top")
		(29 "B.CrtYd" user "Package Geometry/Place Bound Bottom")
		(35 "F.Fab" user "Ref Des/Assembly Top")
		(33 "B.Fab" user "Ref Des/Assembly Bottom")
	)
	(footprint ""
		(layer "F.Cu")
		(at 346.6338 -23.4823)
		(property "Reference" "C7F11"
			(at 0 0 0)
			(layer "F.SilkS")
			(hide yes)
			(effects
				(font
					(size 1.27 1.27)
				)
			)
		)
		(property "Value" ""
			(at 0 0 0)
			(layer "F.Fab")
			(effects
				(font
					(size 1.27 1.27)
				)
			)
		)
		(duplicate_pad_numbers_are_jumpers no)
		(fp_rect
			(start -0.3048 0.9906)
			(end 0.3048 -0.1016)
			(stroke
				(width 0)
				(type default)
			)
			(fill no)
			(layer "F.CrtYd")
		)
		(fp_line
			(start -0.3048 -0.1016)
			(end -0.3048 0.9906)
			(stroke
				(width 0.1)
				(type default)
			)
			(layer "F.Fab")
		)
		(fp_line
			(start -0.3048 0.9906)
			(end 0.3048 0.9906)
			(stroke
				(width 0.1)
				(type default)
			)
			(layer "F.Fab")
		)
		(fp_line
			(start 0.3048 -0.1016)
			(end -0.3048 -0.1016)
			(stroke
				(width 0.1)
				(type default)
			)
			(layer "F.Fab")
		)
		(fp_line
			(start 0.3048 0.9906)
			(end 0.3048 -0.1016)
			(stroke
				(width 0.1)
				(type default)
			)
			(layer "F.Fab")
		)
		(pad "1" smd rect
			(at 0 0)
			(size 0.508 0.508)
			(layers "F.Cu" "F.Mask" "F.Paste")
			(net "PWRGD_PVPP_ABC_R")
		)
		(pad "2" smd rect
			(at 0 0.889)
			(size 0.508 0.508)
			(layers "F.Cu" "F.Mask" "F.Paste")
			(net "GND")
		)
		(zone
			(layer "F.Cu")
			(hatch none 0.5)
			(connect_pads
				(clearance 0)
			)
			(min_thickness 0.25)
			(keepout
				(tracks allowed)
				(vias not_allowed)
				(pads allowed)
				(copperpour not_allowed)
				(footprints allowed)
			)
			(placement
				(enabled no)
				(sheetname "")
			)
			(fill
				(thermal_gap 0.5)
				(thermal_bridge_width 0.5)
				(island_removal_mode 0)
			)
			(polygon
				(pts
					(xy 346.3798 -22.8473) (xy 346.8878 -22.8473) (xy 346.8878 -23.2283) (xy 346.3798 -23.2283)
				)
			)
		)
		(zone
			(layer "F.Cu")
			(hatch none 0.5)
			(connect_pads
				(clearance 0)
			)
			(min_thickness 0.25)
			(keepout
				(tracks not_allowed)
				(vias allowed)
				(pads allowed)
				(copperpour not_allowed)
				(footprints allowed)
			)
			(placement
				(enabled no)
				(sheetname "")
			)
			(fill
				(thermal_gap 0.5)
				(thermal_bridge_width 0.5)
				(island_removal_mode 0)
			)
			(polygon
				(pts
					(xy 346.3798 -22.8473) (xy 346.8878 -22.8473) (xy 346.8878 -23.2283) (xy 346.3798 -23.2283)
				)
			)
		)
	)
	(footprint ""
		(layer "F.Cu")
		(at 112.182402 -77.382116)
		(property "Reference" "C3D14"
			(at 0 0 0)
			(layer "F.SilkS")
			(hide yes)
			(effects
				(font
					(size 1.27 1.27)
				)
			)
		)
		(property "Value" ""
			(at 0 0 0)
			(layer "F.Fab")
			(effects
				(font
					(size 1.27 1.27)
				)
			)
		)
		(duplicate_pad_numbers_are_jumpers no)
		(fp_poly
			(pts
				(xy -0.4953 -0.2032) (xy 0.4953 -0.2032) (xy 0.4953 1.6002) (xy -0.4953 1.6002)
			)
			(stroke
				(width 0)
				(type default)
			)
			(fill no)
			(layer "F.CrtYd")
		)
		(fp_line
			(start -0.4953 -0.2032)
			(end 0.4953 -0.2032)
			(stroke
				(width 0.1)
				(type default)
			)
			(layer "F.Fab")
		)
		(fp_line
			(start -0.4953 1.6002)
			(end -0.4953 -0.2032)
			(stroke
				(width 0.1)
				(type default)
			)
			(layer "F.Fab")
		)
		(fp_line
			(start 0.4953 -0.2032)
			(end 0.4953 1.6002)
			(stroke
				(width 0.1)
				(type default)
			)
			(layer "F.Fab")
		)
		(fp_line
			(start 0.4953 1.6002)
			(end -0.4953 1.6002)
			(stroke
				(width 0.1)
				(type default)
			)
			(layer "F.Fab")
		)
		(pad "1" smd rect
			(at 0 0)
			(size 0.762 0.889)
			(layers "F.Cu" "F.Mask" "F.Paste")
			(net "PVCCMCP_CPU1")
		)
		(pad "2" smd rect
			(at 0 1.397)
			(size 0.762 0.889)
			(layers "F.Cu" "F.Mask" "F.Paste")
			(net "GND")
		)
		(zone
			(layer "F.Cu")
			(hatch none 0.5)
			(connect_pads
				(clearance 0)
			)
			(min_thickness 0.25)
			(keepout
				(tracks not_allowed)
				(vias allowed)
				(pads allowed)
				(copperpour not_allowed)
				(footprints allowed)
			)
			(placement
				(enabled no)
				(sheetname "")
			)
			(fill
				(thermal_gap 0.5)
				(thermal_bridge_width 0.5)
				(island_removal_mode 0)
			)
			(polygon
				(pts
					(xy 111.801402 -76.937616) (xy 112.563402 -76.937616) (xy 112.563402 -76.429616) (xy 111.801402 -76.429616)
				)
			)
		)
	)
	(footprint ""
		(layer "F.Cu")
		(at 13.8938 -36.576 90)
		(property "Reference" "C1F2"
			(at 0 0 90)
			(layer "F.SilkS")
			(hide yes)
			(effects
				(font
					(size 1.27 1.27)
				)
			)
		)
		(property "Value" ""
			(at 0 0 90)
			(layer "F.Fab")
			(effects
				(font
					(size 1.27 1.27)
				)
			)
		)
		(duplicate_pad_numbers_are_jumpers no)
		(fp_rect
			(start -0.3048 -0.1016)
			(end 0.3048 0.9906)
			(stroke
				(width 0)
				(type default)
			)
			(fill no)
			(layer "F.CrtYd")
		)
		(fp_line
			(start 0.3048 -0.1016)
			(end -0.3048 -0.1016)
			(stroke
				(width 0.1)
				(type default)
			)
			(layer "F.Fab")
		)
		(fp_line
			(start -0.3048 -0.1016)
			(end -0.3048 0.9906)
			(stroke
				(width 0.1)
				(type default)
			)
			(layer "F.Fab")
		)
		(fp_line
			(start 0.3048 0.9906)
			(end 0.3048 -0.1016)
			(stroke
				(width 0.1)
				(type default)
			)
			(layer "F.Fab")
		)
		(fp_line
			(start -0.3048 0.9906)
			(end 0.3048 0.9906)
			(stroke
				(width 0.1)
				(type default)
			)
			(layer "F.Fab")
		)
		(pad "1" smd rect
			(at 0 0 90)
			(size 0.508 0.508)
			(layers "F.Cu" "F.Mask" "F.Paste")
			(net "P3E_CPU1_PE3_MP_C_TXP<7>")
		)
		(pad "2" smd rect
			(at 0 0.889 90)
			(size 0.508 0.508)
			(layers "F.Cu" "F.Mask" "F.Paste")
			(net "P3E_CPU1_PE3_MP_TXP<7>")
		)
		(zone
			(layer "F.Cu")
			(hatch none 0.5)
			(connect_pads
				(clearance 0)
			)
			(min_thickness 0.25)
			(keepout
				(tracks allowed)
				(vias not_allowed)
				(pads allowed)
				(copperpour not_allowed)
				(footprints allowed)
			)
			(placement
				(enabled no)
				(sheetname "")
			)
			(fill
				(thermal_gap 0.5)
				(thermal_bridge_width 0.5)
				(island_removal_mode 0)
			)
			(polygon
				(pts
					(xy 14.1478 -36.322) (xy 14.5288 -36.322) (xy 14.5288 -36.83) (xy 14.1478 -36.83)
				)
			)
		)
		(zone
			(layer "F.Cu")
			(hatch none 0.5)
			(connect_pads
				(clearance 0)
			)
			(min_thickness 0.25)
			(keepout
				(tracks not_allowed)
				(vias allowed)
				(pads allowed)
				(copperpour not_allowed)
				(footprints allowed)
			)
			(placement
				(enabled no)
				(sheetname "")
			)
			(fill
				(thermal_gap 0.5)
				(thermal_bridge_width 0.5)
				(island_removal_mode 0)
			)
			(polygon
				(pts
					(xy 14.1478 -36.322) (xy 14.5288 -36.322) (xy 14.5288 -36.83) (xy 14.1478 -36.83)
				)
			)
		)
	)
)
